(kicad_pcb
	(version 20260206)
	(generator "pcbnew")
	(generator_version "10.0")
	(general
		(thickness 1.6)
		(legacy_teardrops no)
	)
	(paper "A4")
	(title_block
		(title "04192023_DAF0TMB3IC0_F0TG_MB_C_brd_V02_OCP.brd")
		(comment 1 "Grand Teton / footprints 2759-2765 of 8354")
	)
	(layers
		(0 "F.Cu" signal "TOP")
		(4 "In1.Cu" signal "GND")
		(6 "In2.Cu" signal "IN1")
		(8 "In3.Cu" signal "GND1")
		(10 "In4.Cu" signal "IN2")
		(12 "In5.Cu" signal "GND2")
		(14 "In6.Cu" signal "IN3")
		(16 "In7.Cu" signal "GND3")
		(18 "In8.Cu" signal "VCC")
		(20 "In9.Cu" signal "VCC1")
		(22 "In10.Cu" signal "GND4")
		(24 "In11.Cu" signal "IN4")
		(26 "In12.Cu" signal "GND5")
		(28 "In13.Cu" signal "IN5")
		(30 "In14.Cu" signal "GND6")
		(32 "In15.Cu" signal "IN6")
		(34 "In16.Cu" signal "GND7")
		(2 "B.Cu" signal "BOTTOM")
		(9 "F.Adhes" user "F.Adhesive")
		(11 "B.Adhes" user "B.Adhesive")
		(13 "F.Paste" user "Package Geometry/Pastemask Top")
		(15 "B.Paste" user "Package Geometry/Pastemask Bottom")
		(5 "F.SilkS" user "Ref Des/Silkscreen Top")
		(7 "B.SilkS" user "Ref Des/Silkscreen Bottom")
		(1 "F.Mask" user "Board Geometry/Soldermask Top")
		(3 "B.Mask" user "Board Geometry/Soldermask Bottom")
		(17 "Dwgs.User" user "User.Drawings")
		(19 "Cmts.User" user "User.Comments")
		(21 "Eco1.User" user "User.Eco1")
		(23 "Eco2.User" user "User.Eco2")
		(25 "Edge.Cuts" user "Board Geometry/Outline")
		(27 "Margin" user)
		(31 "F.CrtYd" user "Package Geometry/Place Bound Top")
		(29 "B.CrtYd" user "Package Geometry/Place Bound Bottom")
		(35 "F.Fab" user "Ref Des/Assembly Top")
		(33 "B.Fab" user "Ref Des/Assembly Bottom")
	)
	(footprint ""
		(layer "F.Cu")
		(at 327.179178 -42.176954)
		(property "Reference" "R2843"
			(at 0 0 0)
			(layer "F.SilkS")
			(hide yes)
			(effects
				(font
					(size 1.27 1.27)
				)
			)
		)
		(property "Value" ""
			(at 0 0 0)
			(layer "F.Fab")
			(effects
				(font
					(size 1.27 1.27)
				)
			)
		)
		(duplicate_pad_numbers_are_jumpers no)
		(fp_line
			(start -0.7874 -0.4064)
			(end 0.7874 -0.4064)
			(stroke
				(width 0.1524)
				(type default)
			)
			(layer "F.SilkS")
		)
		(fp_line
			(start -0.7874 0.4064)
			(end -0.7874 -0.4064)
			(stroke
				(width 0.1524)
				(type default)
			)
			(layer "F.SilkS")
		)
		(fp_line
			(start 0.7874 -0.4064)
			(end 0.7874 0.4064)
			(stroke
				(width 0.1524)
				(type default)
			)
			(layer "F.SilkS")
		)
		(fp_line
			(start 0.7874 0.4064)
			(end -0.7874 0.4064)
			(stroke
				(width 0.1524)
				(type default)
			)
			(layer "F.SilkS")
		)
		(fp_line
			(start -0.67945 -0.305054)
			(end -0.12065 -0.305054)
			(stroke
				(width 0.1)
				(type default)
			)
			(layer "F.Fab")
		)
		(fp_line
			(start -0.67945 0.3048)
			(end -0.67945 -0.305054)
			(stroke
				(width 0.1)
				(type default)
			)
			(layer "F.Fab")
		)
		(fp_line
			(start -0.12065 -0.305054)
			(end -0.12065 -0.2794)
			(stroke
				(width 0.1)
				(type default)
			)
			(layer "F.Fab")
		)
		(fp_line
			(start -0.12065 -0.2794)
			(end 0.12065 -0.2794)
			(stroke
				(width 0.1)
				(type default)
			)
			(layer "F.Fab")
		)
		(fp_line
			(start -0.12065 0.2794)
			(end -0.12065 0.3048)
			(stroke
				(width 0.1)
				(type default)
			)
			(layer "F.Fab")
		)
		(fp_line
			(start -0.12065 0.3048)
			(end -0.67945 0.3048)
			(stroke
				(width 0.1)
				(type default)
			)
			(layer "F.Fab")
		)
		(fp_line
			(start 0.120396 0.2794)
			(end -0.12065 0.2794)
			(stroke
				(width 0.1)
				(type default)
			)
			(layer "F.Fab")
		)
		(fp_line
			(start 0.120396 0.3048)
			(end 0.120396 0.2794)
			(stroke
				(width 0.1)
				(type default)
			)
			(layer "F.Fab")
		)
		(fp_line
			(start 0.12065 -0.3048)
			(end 0.67945 -0.3048)
			(stroke
				(width 0.1)
				(type default)
			)
			(layer "F.Fab")
		)
		(fp_line
			(start 0.12065 -0.2794)
			(end 0.12065 -0.3048)
			(stroke
				(width 0.1)
				(type default)
			)
			(layer "F.Fab")
		)
		(fp_line
			(start 0.67945 -0.3048)
			(end 0.67945 0.3048)
			(stroke
				(width 0.1)
				(type default)
			)
			(layer "F.Fab")
		)
		(fp_line
			(start 0.67945 0.3048)
			(end 0.120396 0.3048)
			(stroke
				(width 0.1)
				(type default)
			)
			(layer "F.Fab")
		)
		(pad "1" smd circle
			(at -0.40005 0)
			(size 0 0)
			(layers "F.Cu" "F.Mask" "F.Paste")
			(net "P3V3_ADC")
		)
		(pad "2" smd circle
			(at 0.40005 0)
			(size 0 0)
			(layers "F.Cu" "F.Mask" "F.Paste")
			(net "GND")
		)
	)
	(footprint ""
		(layer "F.Cu")
		(at 152.270206 -191.35471 -90)
		(property "Reference" "R3201"
			(at 0 0 270)
			(layer "F.SilkS")
			(hide yes)
			(effects
				(font
					(size 1.27 1.27)
				)
			)
		)
		(property "Value" ""
			(at 0 0 270)
			(layer "F.Fab")
			(effects
				(font
					(size 1.27 1.27)
				)
			)
		)
		(duplicate_pad_numbers_are_jumpers no)
		(fp_line
			(start 0.42291 0.4064)
			(end -0.41529 0.4064)
			(stroke
				(width 0.1524)
				(type default)
			)
			(layer "F.SilkS")
		)
		(fp_line
			(start -0.7874 -0.002794)
			(end -0.7874 -0.4064)
			(stroke
				(width 0.1524)
				(type default)
			)
			(layer "F.SilkS")
		)
		(fp_line
			(start -0.7874 -0.4064)
			(end 0.7874 -0.4064)
			(stroke
				(width 0.1524)
				(type default)
			)
			(layer "F.SilkS")
		)
		(fp_line
			(start 0.7874 -0.4064)
			(end 0.7874 -0.002794)
			(stroke
				(width 0.1524)
				(type default)
			)
			(layer "F.SilkS")
		)
		(fp_line
			(start -0.67945 0.3048)
			(end -0.67945 -0.305054)
			(stroke
				(width 0.1)
				(type default)
			)
			(layer "F.Fab")
		)
		(fp_line
			(start -0.12065 0.3048)
			(end -0.67945 0.3048)
			(stroke
				(width 0.1)
				(type default)
			)
			(layer "F.Fab")
		)
		(fp_line
			(start 0.120396 0.3048)
			(end 0.120396 0.2794)
			(stroke
				(width 0.1)
				(type default)
			)
			(layer "F.Fab")
		)
		(fp_line
			(start 0.67945 0.3048)
			(end 0.120396 0.3048)
			(stroke
				(width 0.1)
				(type default)
			)
			(layer "F.Fab")
		)
		(fp_line
			(start -0.12065 0.2794)
			(end -0.12065 0.3048)
			(stroke
				(width 0.1)
				(type default)
			)
			(layer "F.Fab")
		)
		(fp_line
			(start 0.120396 0.2794)
			(end -0.12065 0.2794)
			(stroke
				(width 0.1)
				(type default)
			)
			(layer "F.Fab")
		)
		(fp_line
			(start -0.12065 -0.2794)
			(end 0.12065 -0.2794)
			(stroke
				(width 0.1)
				(type default)
			)
			(layer "F.Fab")
		)
		(fp_line
			(start 0.12065 -0.2794)
			(end 0.12065 -0.3048)
			(stroke
				(width 0.1)
				(type default)
			)
			(layer "F.Fab")
		)
		(fp_line
			(start 0.12065 -0.3048)
			(end 0.67945 -0.3048)
			(stroke
				(width 0.1)
				(type default)
			)
			(layer "F.Fab")
		)
		(fp_line
			(start 0.67945 -0.3048)
			(end 0.67945 0.3048)
			(stroke
				(width 0.1)
				(type default)
			)
			(layer "F.Fab")
		)
		(fp_line
			(start -0.67945 -0.305054)
			(end -0.12065 -0.305054)
			(stroke
				(width 0.1)
				(type default)
			)
			(layer "F.Fab")
		)
		(fp_line
			(start -0.12065 -0.305054)
			(end -0.12065 -0.2794)
			(stroke
				(width 0.1)
				(type default)
			)
			(layer "F.Fab")
		)
		(pad "1" smd circle
			(at -0.40005 0 270)
			(size 0 0)
			(layers "F.Cu" "F.Mask" "F.Paste")
			(net "CLK_100M_CPU1_CLK05_R_DN")
		)
		(pad "2" smd circle
			(at 0.40005 0 270)
			(size 0 0)
			(layers "F.Cu" "F.Mask" "F.Paste")
			(net "CLK_100M_CPU1_CLK05_DN")
		)
	)
	(footprint ""
		(layer "F.Cu")
		(at 120.69826 -30.389576)
		(property "Reference" "R6268"
			(at 0 0 0)
			(layer "F.SilkS")
			(hide yes)
			(effects
				(font
					(size 1.27 1.27)
				)
			)
		)
		(property "Value" ""
			(at 0 0 0)
			(layer "F.Fab")
			(effects
				(font
					(size 1.27 1.27)
				)
			)
		)
		(duplicate_pad_numbers_are_jumpers no)
		(fp_line
			(start -0.7874 -0.4064)
			(end 0.7874 -0.4064)
			(stroke
				(width 0.1524)
				(type default)
			)
			(layer "F.SilkS")
		)
		(fp_line
			(start -0.7874 0.4064)
			(end -0.7874 -0.4064)
			(stroke
				(width 0.1524)
				(type default)
			)
			(layer "F.SilkS")
		)
		(fp_line
			(start 0.7874 -0.4064)
			(end 0.7874 0.4064)
			(stroke
				(width 0.1524)
				(type default)
			)
			(layer "F.SilkS")
		)
		(fp_line
			(start 0.7874 0.4064)
			(end -0.7874 0.4064)
			(stroke
				(width 0.1524)
				(type default)
			)
			(layer "F.SilkS")
		)
		(fp_line
			(start -0.67945 -0.305054)
			(end -0.12065 -0.305054)
			(stroke
				(width 0.1)
				(type default)
			)
			(layer "F.Fab")
		)
		(fp_line
			(start -0.67945 0.3048)
			(end -0.67945 -0.305054)
			(stroke
				(width 0.1)
				(type default)
			)
			(layer "F.Fab")
		)
		(fp_line
			(start -0.12065 -0.305054)
			(end -0.12065 -0.2794)
			(stroke
				(width 0.1)
				(type default)
			)
			(layer "F.Fab")
		)
		(fp_line
			(start -0.12065 -0.2794)
			(end 0.12065 -0.2794)
			(stroke
				(width 0.1)
				(type default)
			)
			(layer "F.Fab")
		)
		(fp_line
			(start -0.12065 0.2794)
			(end -0.12065 0.3048)
			(stroke
				(width 0.1)
				(type default)
			)
			(layer "F.Fab")
		)
		(fp_line
			(start -0.12065 0.3048)
			(end -0.67945 0.3048)
			(stroke
				(width 0.1)
				(type default)
			)
			(layer "F.Fab")
		)
		(fp_line
			(start 0.120396 0.2794)
			(end -0.12065 0.2794)
			(stroke
				(width 0.1)
				(type default)
			)
			(layer "F.Fab")
		)
		(fp_line
			(start 0.120396 0.3048)
			(end 0.120396 0.2794)
			(stroke
				(width 0.1)
				(type default)
			)
			(layer "F.Fab")
		)
		(fp_line
			(start 0.12065 -0.3048)
			(end 0.67945 -0.3048)
			(stroke
				(width 0.1)
				(type default)
			)
			(layer "F.Fab")
		)
		(fp_line
			(start 0.12065 -0.2794)
			(end 0.12065 -0.3048)
			(stroke
				(width 0.1)
				(type default)
			)
			(layer "F.Fab")
		)
		(fp_line
			(start 0.67945 -0.3048)
			(end 0.67945 0.3048)
			(stroke
				(width 0.1)
				(type default)
			)
			(layer "F.Fab")
		)
		(fp_line
			(start 0.67945 0.3048)
			(end 0.120396 0.3048)
			(stroke
				(width 0.1)
				(type default)
			)
			(layer "F.Fab")
		)
		(pad "1" smd circle
			(at -0.40005 0)
			(size 0 0)
			(layers "F.Cu" "F.Mask" "F.Paste")
			(net "USB_HUB2_TI_USB_SSRXM_DN4_MRP_VDD12")
		)
		(pad "2" smd circle
			(at 0.40005 0)
			(size 0 0)
			(layers "F.Cu" "F.Mask" "F.Paste")
			(net "P1V2_CPU0_USB2_DVDD12")
		)
	)
	(footprint ""
		(layer "F.Cu")
		(at 333.219044 -378.95403 -90)
		(property "Reference" "C959"
			(at 0 0 270)
			(layer "F.SilkS")
			(hide yes)
			(effects
				(font
					(size 1.27 1.27)
				)
			)
		)
		(property "Value" ""
			(at 0 0 270)
			(layer "F.Fab")
			(effects
				(font
					(size 1.27 1.27)
				)
			)
		)
		(duplicate_pad_numbers_are_jumpers no)
		(fp_line
			(start -0.299974 0.150114)
			(end -0.299974 -0.150114)
			(stroke
				(width 0.1)
				(type default)
			)
			(layer "F.Fab")
		)
		(fp_line
			(start 0.299974 0.150114)
			(end -0.299974 0.150114)
			(stroke
				(width 0.1)
				(type default)
			)
			(layer "F.Fab")
		)
		(fp_line
			(start -0.299974 -0.150114)
			(end 0.299974 -0.150114)
			(stroke
				(width 0.1)
				(type default)
			)
			(layer "F.Fab")
		)
		(fp_line
			(start 0.299974 -0.150114)
			(end 0.299974 0.150114)
			(stroke
				(width 0.1)
				(type default)
			)
			(layer "F.Fab")
		)
		(pad "1" smd rect
			(at -0.2667 0 270)
			(size 0.3048 0.381)
			(layers "F.Cu" "F.Mask" "F.Paste")
			(net "P5E_CPU0_P1_TX_C_DP<3>")
		)
		(pad "2" smd rect
			(at 0.2667 0 270)
			(size 0.3048 0.381)
			(layers "F.Cu" "F.Mask" "F.Paste")
			(net "P5E_CPU0_P1_TX_DP<3>")
		)
	)
	(footprint ""
		(layer "F.Cu")
		(at 455.534776 -46.264576 -90)
		(property "Reference" "PC569"
			(at 0 0 270)
			(layer "F.SilkS")
			(hide yes)
			(effects
				(font
					(size 1.27 1.27)
				)
			)
		)
		(property "Value" ""
			(at 0 0 270)
			(layer "F.Fab")
			(effects
				(font
					(size 1.27 1.27)
				)
			)
		)
		(duplicate_pad_numbers_are_jumpers no)
		(fp_line
			(start -0.7874 0.4064)
			(end -0.7874 -0.4064)
			(stroke
				(width 0.1524)
				(type default)
			)
			(layer "F.SilkS")
		)
		(fp_line
			(start 0.7874 0.4064)
			(end -0.7874 0.4064)
			(stroke
				(width 0.1524)
				(type default)
			)
			(layer "F.SilkS")
		)
		(fp_line
			(start -0.7874 -0.4064)
			(end 0.7874 -0.4064)
			(stroke
				(width 0.1524)
				(type default)
			)
			(layer "F.SilkS")
		)
		(fp_line
			(start 0.7874 -0.4064)
			(end 0.7874 0.4064)
			(stroke
				(width 0.1524)
				(type default)
			)
			(layer "F.SilkS")
		)
		(fp_line
			(start -0.67945 0.3048)
			(end -0.67945 -0.305054)
			(stroke
				(width 0.1)
				(type default)
			)
			(layer "F.Fab")
		)
		(fp_line
			(start -0.12065 0.3048)
			(end -0.67945 0.3048)
			(stroke
				(width 0.1)
				(type default)
			)
			(layer "F.Fab")
		)
		(fp_line
			(start 0.120396 0.3048)
			(end 0.120396 0.2794)
			(stroke
				(width 0.1)
				(type default)
			)
			(layer "F.Fab")
		)
		(fp_line
			(start 0.67945 0.3048)
			(end 0.120396 0.3048)
			(stroke
				(width 0.1)
				(type default)
			)
			(layer "F.Fab")
		)
		(fp_line
			(start -0.12065 0.2794)
			(end -0.12065 0.3048)
			(stroke
				(width 0.1)
				(type default)
			)
			(layer "F.Fab")
		)
		(fp_line
			(start 0.120396 0.2794)
			(end -0.12065 0.2794)
			(stroke
				(width 0.1)
				(type default)
			)
			(layer "F.Fab")
		)
		(fp_line
			(start -0.12065 -0.2794)
			(end 0.12065 -0.2794)
			(stroke
				(width 0.1)
				(type default)
			)
			(layer "F.Fab")
		)
		(fp_line
			(start 0.12065 -0.2794)
			(end 0.12065 -0.3048)
			(stroke
				(width 0.1)
				(type default)
			)
			(layer "F.Fab")
		)
		(fp_line
			(start 0.12065 -0.3048)
			(end 0.67945 -0.3048)
			(stroke
				(width 0.1)
				(type default)
			)
			(layer "F.Fab")
		)
		(fp_line
			(start 0.67945 -0.3048)
			(end 0.67945 0.3048)
			(stroke
				(width 0.1)
				(type default)
			)
			(layer "F.Fab")
		)
		(fp_line
			(start -0.67945 -0.305054)
			(end -0.12065 -0.305054)
			(stroke
				(width 0.1)
				(type default)
			)
			(layer "F.Fab")
		)
		(fp_line
			(start -0.12065 -0.305054)
			(end -0.12065 -0.2794)
			(stroke
				(width 0.1)
				(type default)
			)
			(layer "F.Fab")
		)
		(pad "1" smd circle
			(at -0.40005 0 270)
			(size 0 0)
			(layers "F.Cu" "F.Mask" "F.Paste")
			(net "P3V3_AUX_FB")
		)
		(pad "2" smd circle
			(at 0.40005 0 270)
			(size 0 0)
			(layers "F.Cu" "F.Mask" "F.Paste")
			(net "P3V3_AUX")
		)
	)
	(footprint ""
		(layer "F.Cu")
		(at 38.697662 -419.249098 90)
		(property "Reference" "R3266"
			(at 0 0 90)
			(layer "F.SilkS")
			(hide yes)
			(effects
				(font
					(size 1.27 1.27)
				)
			)
		)
		(property "Value" ""
			(at 0 0 90)
			(layer "F.Fab")
			(effects
				(font
					(size 1.27 1.27)
				)
			)
		)
		(duplicate_pad_numbers_are_jumpers no)
		(fp_line
			(start 0.7874 -0.4064)
			(end 0.7874 0.4064)
			(stroke
				(width 0.1524)
				(type default)
			)
			(layer "F.SilkS")
		)
		(fp_line
			(start -0.7874 -0.4064)
			(end 0.7874 -0.4064)
			(stroke
				(width 0.1524)
				(type default)
			)
			(layer "F.SilkS")
		)
		(fp_line
			(start 0.7874 0.4064)
			(end -0.7874 0.4064)
			(stroke
				(width 0.1524)
				(type default)
			)
			(layer "F.SilkS")
		)
		(fp_line
			(start -0.7874 0.4064)
			(end -0.7874 -0.4064)
			(stroke
				(width 0.1524)
				(type default)
			)
			(layer "F.SilkS")
		)
		(fp_line
			(start -0.12065 -0.305054)
			(end -0.12065 -0.2794)
			(stroke
				(width 0.1)
				(type default)
			)
			(layer "F.Fab")
		)
		(fp_line
			(start -0.67945 -0.305054)
			(end -0.12065 -0.305054)
			(stroke
				(width 0.1)
				(type default)
			)
			(layer "F.Fab")
		)
		(fp_line
			(start 0.67945 -0.3048)
			(end 0.67945 0.3048)
			(stroke
				(width 0.1)
				(type default)
			)
			(layer "F.Fab")
		)
		(fp_line
			(start 0.12065 -0.3048)
			(end 0.67945 -0.3048)
			(stroke
				(width 0.1)
				(type default)
			)
			(layer "F.Fab")
		)
		(fp_line
			(start 0.12065 -0.2794)
			(end 0.12065 -0.3048)
			(stroke
				(width 0.1)
				(type default)
			)
			(layer "F.Fab")
		)
		(fp_line
			(start -0.12065 -0.2794)
			(end 0.12065 -0.2794)
			(stroke
				(width 0.1)
				(type default)
			)
			(layer "F.Fab")
		)
		(fp_line
			(start 0.120396 0.2794)
			(end -0.12065 0.2794)
			(stroke
				(width 0.1)
				(type default)
			)
			(layer "F.Fab")
		)
		(fp_line
			(start -0.12065 0.2794)
			(end -0.12065 0.3048)
			(stroke
				(width 0.1)
				(type default)
			)
			(layer "F.Fab")
		)
		(fp_line
			(start 0.67945 0.3048)
			(end 0.120396 0.3048)
			(stroke
				(width 0.1)
				(type default)
			)
			(layer "F.Fab")
		)
		(fp_line
			(start 0.120396 0.3048)
			(end 0.120396 0.2794)
			(stroke
				(width 0.1)
				(type default)
			)
			(layer "F.Fab")
		)
		(fp_line
			(start -0.12065 0.3048)
			(end -0.67945 0.3048)
			(stroke
				(width 0.1)
				(type default)
			)
			(layer "F.Fab")
		)
		(fp_line
			(start -0.67945 0.3048)
			(end -0.67945 -0.305054)
			(stroke
				(width 0.1)
				(type default)
			)
			(layer "F.Fab")
		)
		(pad "1" smd circle
			(at -0.40005 0 90)
			(size 0 0)
			(layers "F.Cu" "F.Mask" "F.Paste")
			(net "P3V3_AUX")
		)
		(pad "2" smd circle
			(at 0.40005 0 90)
			(size 0 0)
			(layers "F.Cu" "F.Mask" "F.Paste")
			(net "FM_P2E_MODE")
		)
	)
	(footprint ""
		(layer "F.Cu")
		(at 426.213778 -398.71523)
		(property "Reference" "C798"
			(at 0 0 0)
			(layer "F.SilkS")
			(hide yes)
			(effects
				(font
					(size 1.27 1.27)
				)
			)
		)
		(property "Value" ""
			(at 0 0 0)
			(layer "F.Fab")
			(effects
				(font
					(size 1.27 1.27)
				)
			)
		)
		(duplicate_pad_numbers_are_jumpers no)
		(fp_line
			(start -1.524 -0.762)
			(end 1.524 -0.762)
			(stroke
				(width 0.1524)
				(type default)
			)
			(layer "F.SilkS")
		)
		(fp_line
			(start -1.524 0.762)
			(end -1.524 -0.762)
			(stroke
				(width 0.1524)
				(type default)
			)
			(layer "F.SilkS")
		)
		(fp_line
			(start 1.524 -0.762)
			(end 1.524 0.762)
			(stroke
				(width 0.1524)
				(type default)
			)
			(layer "F.SilkS")
		)
		(fp_line
			(start 1.524 0.762)
			(end -1.524 0.762)
			(stroke
				(width 0.1524)
				(type default)
			)
			(layer "F.SilkS")
		)
		(fp_line
			(start -1.1049 -0.724916)
			(end -1.1049 0.724916)
			(stroke
				(width 0.1)
				(type default)
			)
			(layer "F.Fab")
		)
		(fp_line
			(start -1.1049 0.724916)
			(end 1.1049 0.724916)
			(stroke
				(width 0.1)
				(type default)
			)
			(layer "F.Fab")
		)
		(fp_line
			(start 1.1049 -0.724916)
			(end -1.1049 -0.724916)
			(stroke
				(width 0.1)
				(type default)
			)
			(layer "F.Fab")
		)
		(fp_line
			(start 1.1049 0.724916)
			(end 1.1049 -0.724916)
			(stroke
				(width 0.1)
				(type default)
			)
			(layer "F.Fab")
		)
		(pad "1" smd rect
			(at -0.889 0 180)
			(size 1.016 1.27)
			(layers "F.Cu" "F.Mask" "F.Paste")
			(net "P0V9_CPU0_RT2_2A")
		)
		(pad "2" smd rect
			(at 0.889 0 180)
			(size 1.016 1.27)
			(layers "F.Cu" "F.Mask" "F.Paste")
			(net "GND")
		)
	)
)
